# GMSL Serializer — assets/stackup.csv
Name;Type;Material;Thickness[mm];Constant
F.Mask;Top Solder Mask;;0.02;
F.Cu;copper;;0.018;
dielectric 1;prepreg;IS400 PR2116;0.12;4.06
In1.Cu;copper;;0.035;
dielectric 2;core;FR-4;1.2;4.35
In2.Cu;copper;;0.035;
dielectric 3;prepreg;IS400 PR2116;0.12;4.06
B.Cu;copper;;0.018;
B.Mask;Bottom Solder Mask;;0.02;
